FILE_TYPE = MULTI_PHYS_TABLE;
PART 'CAPTIVE_SCREW'
CLASS='MECHANICAL'
{==================================================================================================================================================================================================}
:PACK_TYPE | MATERIAL | PART_NUMBER     = EnvComp | PART_NUMBER  | DESCRIPTION                                      | COMPONENT_TYPE  | JEDEC_TYPE   | HEIGHT     | LEAD_LENGTH | SPEED_URL | Status |RPL| AML | Bus_Unit | Days ;
{==================================================================================================================================================================================================}
'TH'       | 'HDW'    | 'H57868-001'(!) = ''      | 'H57868-001' | 'SCR,CPT,PHL,MACH,M3x0.5,15.5mm,STL,NONE'        | 'PSEUDO'        | 'CPTSC220B'  | '0.598 IN' | '0.035'     | 'http://speed.intel.com:8081/speed/module/pdm/item/pdm_item_detail_direct.asp?item_cde=H57868-001&item_rev=01&url_param=unused' | '' | '' | '' | '' | '' 
'TH'       | 'EMPTY'  | 'H57868-001'(!) = ''      | 'H57868-001' | 'SCR,CPT,PHL,MACH,M3x0.5,15.5mm,STL,NONE'        | 'PSEUDO'        | 'CPTSC220B'  | '0.598 IN' | '0.035'     | 'http://speed.intel.com:8081/speed/module/pdm/item/pdm_item_detail_direct.asp?item_cde=H57868-001&item_rev=01&url_param=unused' | '' | '' | '' | '' | ''
END_PART
END.
